# T6G (Grand Teton) — schematic netlist excerpt (pin names and nets, part order shuffled) for the footprints in the layout excerpt that follows; sources: Cadence DE-HDL packaged netlist, KiCad conversion of 04192023_DAF0TMB3IC0_F0TG_MB_C_brd_V02_OCP.brd

C6535  Q_CAP_DIFFBUS  DIFF BUS_0.22UF 6.3V 20% X6S  pkg C0201  page 286 : \1\ = P5E_CPU0_P1_TX_BUF_C_DP<1> ; \2\ = P5E_CPU0_P1_TX_BUF_DP<1>
C6102  Q_CAP  1PF 50V 0.05P COG  pkg C0402  page 179 : A = P3V3_AUX_CPU0_USB2_AVDD33 ; B = GND
R6859  Q_RES  0 5% CHIP  pkg 0402LF  page 151 : A = SMB_VR_3V3STBY_SDA ; B = P0V9_RETIMER_CPU1_PMSDA

(kicad_pcb
	(version 20260206)
	(generator "pcbnew")
	(generator_version "10.0")
	(general
		(thickness 1.6)
		(legacy_teardrops no)
	)
	(paper "A4")
	(title_block
		(title "04192023_DAF0TMB3IC0_F0TG_MB_C_brd_V02_OCP.brd")
		(comment 1 "Grand Teton / footprints 8270-8272 of 8354")
	)
	(layers
		(0 "F.Cu" signal "TOP")
		(4 "In1.Cu" signal "GND")
		(6 "In2.Cu" signal "IN1")
		(8 "In3.Cu" signal "GND1")
		(10 "In4.Cu" signal "IN2")
		(12 "In5.Cu" signal "GND2")
		(14 "In6.Cu" signal "IN3")
		(16 "In7.Cu" signal "GND3")
		(18 "In8.Cu" signal "VCC")
		(20 "In9.Cu" signal "VCC1")
		(22 "In10.Cu" signal "GND4")
		(24 "In11.Cu" signal "IN4")
		(26 "In12.Cu" signal "GND5")
		(28 "In13.Cu" signal "IN5")
		(30 "In14.Cu" signal "GND6")
		(32 "In15.Cu" signal "IN6")
		(34 "In16.Cu" signal "GND7")
		(2 "B.Cu" signal "BOTTOM")
		(9 "F.Adhes" user "F.Adhesive")
		(11 "B.Adhes" user "B.Adhesive")
		(13 "F.Paste" user "Package Geometry/Pastemask Top")
		(15 "B.Paste" user "Package Geometry/Pastemask Bottom")
		(5 "F.SilkS" user "Ref Des/Silkscreen Top")
		(7 "B.SilkS" user "Ref Des/Silkscreen Bottom")
		(1 "F.Mask" user "Board Geometry/Soldermask Top")
		(3 "B.Mask" user "Board Geometry/Soldermask Bottom")
		(17 "Dwgs.User" user "User.Drawings")
		(19 "Cmts.User" user "User.Comments")
		(21 "Eco1.User" user "User.Eco1")
		(23 "Eco2.User" user "User.Eco2")
		(25 "Edge.Cuts" user "Board Geometry/Outline")
		(27 "Margin" user)
		(31 "F.CrtYd" user "Package Geometry/Place Bound Top")
		(29 "B.CrtYd" user "Package Geometry/Place Bound Bottom")
		(35 "F.Fab" user "Ref Des/Assembly Top")
		(33 "B.Fab" user "Ref Des/Assembly Bottom")
	)
	(footprint ""
		(layer "B.Cu")
		(at 13.65885 -402.839174 180)
		(property "Reference" "R6859"
			(at 0 0 0)
			(layer "B.SilkS")
			(hide yes)
			(effects
				(font
					(size 1.27 1.27)
				)
				(justify mirror)
			)
		)
		(property "Value" ""
			(at 0 0 0)
			(layer "B.Fab")
			(effects
				(font
					(size 1.27 1.27)
				)
				(justify mirror)
			)
		)
		(duplicate_pad_numbers_are_jumpers no)
		(fp_line
			(start 0.7874 0.4064)
			(end 0.7874 -0.4064)
			(stroke
				(width 0.1524)
				(type default)
			)
			(layer "B.SilkS")
		)
		(fp_line
			(start 0.7874 -0.4064)
			(end -0.7874 -0.4064)
			(stroke
				(width 0.1524)
				(type default)
			)
			(layer "B.SilkS")
		)
		(fp_line
			(start -0.7874 0.4064)
			(end 0.7874 0.4064)
			(stroke
				(width 0.1524)
				(type default)
			)
			(layer "B.SilkS")
		)
		(fp_line
			(start -0.7874 -0.4064)
			(end -0.7874 0.4064)
			(stroke
				(width 0.1524)
				(type default)
			)
			(layer "B.SilkS")
		)
		(fp_line
			(start 0.67945 0.3048)
			(end 0.67945 -0.305054)
			(stroke
				(width 0.1)
				(type default)
			)
			(layer "B.Fab")
		)
		(fp_line
			(start 0.67945 -0.305054)
			(end 0.12065 -0.305054)
			(stroke
				(width 0.1)
				(type default)
			)
			(layer "B.Fab")
		)
		(fp_line
			(start 0.12065 0.3048)
			(end 0.67945 0.3048)
			(stroke
				(width 0.1)
				(type default)
			)
			(layer "B.Fab")
		)
		(fp_line
			(start 0.12065 0.2794)
			(end 0.12065 0.3048)
			(stroke
				(width 0.1)
				(type default)
			)
			(layer "B.Fab")
		)
		(fp_line
			(start 0.12065 -0.2794)
			(end -0.12065 -0.2794)
			(stroke
				(width 0.1)
				(type default)
			)
			(layer "B.Fab")
		)
		(fp_line
			(start 0.12065 -0.305054)
			(end 0.12065 -0.2794)
			(stroke
				(width 0.1)
				(type default)
			)
			(layer "B.Fab")
		)
		(fp_line
			(start -0.120396 0.3048)
			(end -0.120396 0.2794)
			(stroke
				(width 0.1)
				(type default)
			)
			(layer "B.Fab")
		)
		(fp_line
			(start -0.120396 0.2794)
			(end 0.12065 0.2794)
			(stroke
				(width 0.1)
				(type default)
			)
			(layer "B.Fab")
		)
		(fp_line
			(start -0.12065 -0.2794)
			(end -0.12065 -0.3048)
			(stroke
				(width 0.1)
				(type default)
			)
			(layer "B.Fab")
		)
		(fp_line
			(start -0.12065 -0.3048)
			(end -0.67945 -0.3048)
			(stroke
				(width 0.1)
				(type default)
			)
			(layer "B.Fab")
		)
		(fp_line
			(start -0.67945 0.3048)
			(end -0.120396 0.3048)
			(stroke
				(width 0.1)
				(type default)
			)
			(layer "B.Fab")
		)
		(fp_line
			(start -0.67945 -0.3048)
			(end -0.67945 0.3048)
			(stroke
				(width 0.1)
				(type default)
			)
			(layer "B.Fab")
		)
		(pad "1" smd circle
			(at 0.40005 0)
			(size 0 0)
			(layers "B.Cu" "B.Mask" "B.Paste")
			(net "SMB_VR_3V3STBY_SDA")
		)
		(pad "2" smd circle
			(at -0.40005 0)
			(size 0 0)
			(layers "B.Cu" "B.Mask" "B.Paste")
			(net "P0V9_RETIMER_CPU1_PMSDA")
		)
	)
	(footprint ""
		(layer "B.Cu")
		(at 309.277766 -416.899344 90)
		(property "Reference" "C6535"
			(at 0 0 90)
			(layer "B.SilkS")
			(hide yes)
			(effects
				(font
					(size 1.27 1.27)
				)
				(justify mirror)
			)
		)
		(property "Value" ""
			(at 0 0 90)
			(layer "B.Fab")
			(effects
				(font
					(size 1.27 1.27)
				)
				(justify mirror)
			)
		)
		(duplicate_pad_numbers_are_jumpers no)
		(fp_line
			(start 0.299974 -0.150114)
			(end -0.299974 -0.150114)
			(stroke
				(width 0.1)
				(type default)
			)
			(layer "B.Fab")
		)
		(fp_line
			(start -0.299974 -0.150114)
			(end -0.299974 0.150114)
			(stroke
				(width 0.1)
				(type default)
			)
			(layer "B.Fab")
		)
		(fp_line
			(start 0.299974 0.150114)
			(end 0.299974 -0.150114)
			(stroke
				(width 0.1)
				(type default)
			)
			(layer "B.Fab")
		)
		(fp_line
			(start -0.299974 0.150114)
			(end 0.299974 0.150114)
			(stroke
				(width 0.1)
				(type default)
			)
			(layer "B.Fab")
		)
		(pad "1" smd rect
			(at 0.2667 0 270)
			(size 0.3048 0.381)
			(layers "B.Cu" "B.Mask" "B.Paste")
			(net "P5E_CPU0_P1_TX_BUF_C_DP<1>")
		)
		(pad "2" smd rect
			(at -0.2667 0 270)
			(size 0.3048 0.381)
			(layers "B.Cu" "B.Mask" "B.Paste")
			(net "P5E_CPU0_P1_TX_BUF_DP<1>")
		)
	)
	(footprint ""
		(layer "B.Cu")
		(at 107.200192 -29.55544 -90)
		(property "Reference" "C6102"
			(at 0 0 90)
			(layer "B.SilkS")
			(hide yes)
			(effects
				(font
					(size 1.27 1.27)
				)
				(justify mirror)
			)
		)
		(property "Value" ""
			(at 0 0 90)
			(layer "B.Fab")
			(effects
				(font
					(size 1.27 1.27)
				)
				(justify mirror)
			)
		)
		(duplicate_pad_numbers_are_jumpers no)
		(fp_line
			(start -0.7874 0.4064)
			(end 0.7874 0.4064)
			(stroke
				(width 0.1524)
				(type default)
			)
			(layer "B.SilkS")
		)
		(fp_line
			(start 0.7874 0.4064)
			(end 0.7874 -0.4064)
			(stroke
				(width 0.1524)
				(type default)
			)
			(layer "B.SilkS")
		)
		(fp_line
			(start -0.7874 -0.4064)
			(end -0.7874 0.4064)
			(stroke
				(width 0.1524)
				(type default)
			)
			(layer "B.SilkS")
		)
		(fp_line
			(start 0.7874 -0.4064)
			(end -0.7874 -0.4064)
			(stroke
				(width 0.1524)
				(type default)
			)
			(layer "B.SilkS")
		)
		(fp_line
			(start -0.67945 0.3048)
			(end -0.120396 0.3048)
			(stroke
				(width 0.1)
				(type default)
			)
			(layer "B.Fab")
		)
		(fp_line
			(start -0.120396 0.3048)
			(end -0.120396 0.2794)
			(stroke
				(width 0.1)
				(type default)
			)
			(layer "B.Fab")
		)
		(fp_line
			(start 0.12065 0.3048)
			(end 0.67945 0.3048)
			(stroke
				(width 0.1)
				(type default)
			)
			(layer "B.Fab")
		)
		(fp_line
			(start 0.67945 0.3048)
			(end 0.67945 -0.305054)
			(stroke
				(width 0.1)
				(type default)
			)
			(layer "B.Fab")
		)
		(fp_line
			(start -0.120396 0.2794)
			(end 0.12065 0.2794)
			(stroke
				(width 0.1)
				(type default)
			)
			(layer "B.Fab")
		)
		(fp_line
			(start 0.12065 0.2794)
			(end 0.12065 0.3048)
			(stroke
				(width 0.1)
				(type default)
			)
			(layer "B.Fab")
		)
		(fp_line
			(start -0.12065 -0.2794)
			(end -0.12065 -0.3048)
			(stroke
				(width 0.1)
				(type default)
			)
			(layer "B.Fab")
		)
		(fp_line
			(start 0.12065 -0.2794)
			(end -0.12065 -0.2794)
			(stroke
				(width 0.1)
				(type default)
			)
			(layer "B.Fab")
		)
		(fp_line
			(start -0.67945 -0.3048)
			(end -0.67945 0.3048)
			(stroke
				(width 0.1)
				(type default)
			)
			(layer "B.Fab")
		)
		(fp_line
			(start -0.12065 -0.3048)
			(end -0.67945 -0.3048)
			(stroke
				(width 0.1)
				(type default)
			)
			(layer "B.Fab")
		)
		(fp_line
			(start 0.12065 -0.305054)
			(end 0.12065 -0.2794)
			(stroke
				(width 0.1)
				(type default)
			)
			(layer "B.Fab")
		)
		(fp_line
			(start 0.67945 -0.305054)
			(end 0.12065 -0.305054)
			(stroke
				(width 0.1)
				(type default)
			)
			(layer "B.Fab")
		)
		(pad "1" smd circle
			(at 0.40005 0 90)
			(size 0 0)
			(layers "B.Cu" "B.Mask" "B.Paste")
			(net "P3V3_AUX_CPU0_USB2_AVDD33")
		)
		(pad "2" smd circle
			(at -0.40005 0 90)
			(size 0 0)
			(layers "B.Cu" "B.Mask" "B.Paste")
			(net "GND")
		)
	)
)
